(kicad_pcb
	(version 20260206)
	(generator "pcbnew")
	(generator_version "10.0")
	(general
		(thickness 1.6)
		(legacy_teardrops no)
	)
	(paper "A4")
	(title_block
		(title "v1-pdb — T6M_PDB_D_0927_0900.brd")
		(comment 1 "Open CloudServer (Microsoft) / footprints 284-290 of 321")
	)
	(layers
		(0 "F.Cu" signal "TOP")
		(4 "In1.Cu" signal "GND")
		(6 "In2.Cu" signal "IN1")
		(8 "In3.Cu" signal "VCC")
		(10 "In4.Cu" signal "VCC1")
		(12 "In5.Cu" signal "IN2")
		(14 "In6.Cu" signal "GND1")
		(2 "B.Cu" signal "BOTTOM")
		(9 "F.Adhes" user "F.Adhesive")
		(11 "B.Adhes" user "B.Adhesive")
		(13 "F.Paste" user "Package Geometry/Pastemask Top")
		(15 "B.Paste" user "Package Geometry/Pastemask Bottom")
		(5 "F.SilkS" user "Ref Des/Silkscreen Top")
		(7 "B.SilkS" user "Ref Des/Silkscreen Bottom")
		(1 "F.Mask" user "Board Geometry/Soldermask Top")
		(3 "B.Mask" user "Board Geometry/Soldermask Bottom")
		(17 "Dwgs.User" user "User.Drawings")
		(19 "Cmts.User" user "User.Comments")
		(21 "Eco1.User" user "User.Eco1")
		(23 "Eco2.User" user "User.Eco2")
		(25 "Edge.Cuts" user "Board Geometry/Outline")
		(27 "Margin" user)
		(31 "F.CrtYd" user "Package Geometry/Place Bound Top")
		(29 "B.CrtYd" user "Package Geometry/Place Bound Bottom")
		(35 "F.Fab" user "Ref Des/Assembly Top")
		(33 "B.Fab" user "Ref Des/Assembly Bottom")
	)
	(footprint ""
		(layer "F.Cu")
		(at 66.891916 -29.351986 180)
		(property "Reference" "R112"
			(at 1.430782 -1.257046 0)
			(unlocked yes)
			(layer "F.SilkS")
			(effects
				(font
					(size 0.7874 0.5842)
					(thickness 0.1524)
				)
				(justify left)
			)
		)
		(property "Value" ""
			(at 0 0 180)
			(layer "F.Fab")
			(effects
				(font
					(size 1.27 1.27)
				)
			)
		)
		(duplicate_pad_numbers_are_jumpers no)
		(fp_line
			(start 0.7874 0.4064)
			(end -0.7874 0.4064)
			(stroke
				(width 0.1524)
				(type default)
			)
			(layer "F.SilkS")
		)
		(fp_line
			(start 0.7874 -0.4064)
			(end 0.7874 0.4064)
			(stroke
				(width 0.1524)
				(type default)
			)
			(layer "F.SilkS")
		)
		(fp_line
			(start -0.7874 0.4064)
			(end -0.7874 -0.4064)
			(stroke
				(width 0.1524)
				(type default)
			)
			(layer "F.SilkS")
		)
		(fp_line
			(start -0.7874 -0.4064)
			(end 0.7874 -0.4064)
			(stroke
				(width 0.1524)
				(type default)
			)
			(layer "F.SilkS")
		)
		(fp_poly
			(pts
				(xy -0.508 0.2794) (xy -0.508 0.2286) (xy -0.635 0.2286) (xy -0.635 -0.254) (xy -0.5334 -0.254)
				(xy -0.5334 -0.2794) (xy 0.5334 -0.2794) (xy 0.5334 -0.254) (xy 0.635 -0.254) (xy 0.635 0.254) (xy 0.5334 0.254)
				(xy 0.5334 0.2794)
			)
			(stroke
				(width 0)
				(type default)
			)
			(fill no)
			(layer "F.CrtYd")
		)
		(pad "1" smd rect
			(at 0.40005 0 180)
			(size 0.4572 0.508)
			(layers "F.Cu" "F.Mask" "F.Paste")
			(net "PSU1_REMOTE_R2_N")
		)
		(pad "2" smd rect
			(at -0.40005 0 180)
			(size 0.4572 0.508)
			(layers "F.Cu" "F.Mask" "F.Paste")
			(net "GND")
		)
	)
	(footprint ""
		(layer "F.Cu")
		(at 71.45147 -220.425772 90)
		(property "Reference" "C40"
			(at -3.909568 -0.112014 90)
			(unlocked yes)
			(layer "F.SilkS")
			(effects
				(font
					(size 0.7874 0.5842)
					(thickness 0.1524)
				)
				(justify left)
			)
		)
		(property "Value" ""
			(at 0 0 90)
			(layer "F.Fab")
			(effects
				(font
					(size 1.27 1.27)
				)
			)
		)
		(duplicate_pad_numbers_are_jumpers no)
		(fp_line
			(start 0.7874 -0.4064)
			(end 0.7874 0.4064)
			(stroke
				(width 0.1524)
				(type default)
			)
			(layer "F.SilkS")
		)
		(fp_line
			(start -0.7874 -0.4064)
			(end 0.7874 -0.4064)
			(stroke
				(width 0.1524)
				(type default)
			)
			(layer "F.SilkS")
		)
		(fp_line
			(start 0 0.381)
			(end 0 -0.381)
			(stroke
				(width 0.1524)
				(type default)
			)
			(layer "F.SilkS")
		)
		(fp_line
			(start 0.7874 0.4064)
			(end -0.7874 0.4064)
			(stroke
				(width 0.1524)
				(type default)
			)
			(layer "F.SilkS")
		)
		(fp_line
			(start -0.7874 0.4064)
			(end -0.7874 -0.4064)
			(stroke
				(width 0.1524)
				(type default)
			)
			(layer "F.SilkS")
		)
		(fp_poly
			(pts
				(xy -0.5334 0.254) (xy -0.635 0.254) (xy -0.635 0.2286) (xy -0.635 -0.254) (xy -0.5334 -0.254) (xy -0.5334 -0.2794)
				(xy 0.5334 -0.2794) (xy 0.5334 -0.254) (xy 0.635 -0.254) (xy 0.635 0.254) (xy 0.5334 0.254) (xy 0.5334 0.2794)
				(xy -0.508 0.2794) (xy -0.5334 0.2794)
			)
			(stroke
				(width 0)
				(type default)
			)
			(fill no)
			(layer "F.CrtYd")
		)
		(pad "1" smd rect
			(at 0.40005 0 90)
			(size 0.4572 0.508)
			(layers "F.Cu" "F.Mask" "F.Paste")
			(net "P12V")
		)
		(pad "2" smd rect
			(at -0.40005 0 90)
			(size 0.4572 0.508)
			(layers "F.Cu" "F.Mask" "F.Paste")
			(net "GND")
		)
	)
	(footprint ""
		(layer "F.Cu")
		(at 26.125678 -278.486362 180)
		(property "Reference" "R52"
			(at 3.845306 0.107188 0)
			(unlocked yes)
			(layer "F.SilkS")
			(effects
				(font
					(size 0.7874 0.5842)
					(thickness 0.1524)
				)
				(justify left)
			)
		)
		(property "Value" ""
			(at 0 0 180)
			(layer "F.Fab")
			(effects
				(font
					(size 1.27 1.27)
				)
			)
		)
		(duplicate_pad_numbers_are_jumpers no)
		(fp_line
			(start 0.7874 0.4064)
			(end -0.7874 0.4064)
			(stroke
				(width 0.1524)
				(type default)
			)
			(layer "F.SilkS")
		)
		(fp_line
			(start 0.7874 -0.4064)
			(end 0.7874 0.4064)
			(stroke
				(width 0.1524)
				(type default)
			)
			(layer "F.SilkS")
		)
		(fp_line
			(start -0.7874 0.4064)
			(end -0.7874 -0.4064)
			(stroke
				(width 0.1524)
				(type default)
			)
			(layer "F.SilkS")
		)
		(fp_line
			(start -0.7874 -0.4064)
			(end 0.7874 -0.4064)
			(stroke
				(width 0.1524)
				(type default)
			)
			(layer "F.SilkS")
		)
		(fp_poly
			(pts
				(xy -0.508 0.2794) (xy -0.508 0.2286) (xy -0.635 0.2286) (xy -0.635 -0.254) (xy -0.5334 -0.254)
				(xy -0.5334 -0.2794) (xy 0.5334 -0.2794) (xy 0.5334 -0.254) (xy 0.635 -0.254) (xy 0.635 0.254) (xy 0.5334 0.254)
				(xy 0.5334 0.2794)
			)
			(stroke
				(width 0)
				(type default)
			)
			(fill no)
			(layer "F.CrtYd")
		)
		(pad "1" smd rect
			(at 0.40005 0 180)
			(size 0.4572 0.508)
			(layers "F.Cu" "F.Mask" "F.Paste")
			(net "GND")
		)
		(pad "2" smd rect
			(at -0.40005 0 180)
			(size 0.4572 0.508)
			(layers "F.Cu" "F.Mask" "F.Paste")
			(net "PSU4_PS_ON_N")
		)
	)
	(footprint ""
		(layer "F.Cu")
		(at 16.21028 -146.178778 -90)
		(property "Reference" "R149"
			(at 1.268476 -0.9398 90)
			(unlocked yes)
			(layer "F.SilkS")
			(effects
				(font
					(size 0.7874 0.5842)
					(thickness 0.1524)
				)
				(justify left)
			)
		)
		(property "Value" ""
			(at 0 0 270)
			(layer "F.Fab")
			(effects
				(font
					(size 1.27 1.27)
				)
			)
		)
		(duplicate_pad_numbers_are_jumpers no)
		(fp_line
			(start -0.7874 0.4064)
			(end -0.7874 -0.4064)
			(stroke
				(width 0.1524)
				(type default)
			)
			(layer "F.SilkS")
		)
		(fp_line
			(start 0.7874 0.4064)
			(end -0.7874 0.4064)
			(stroke
				(width 0.1524)
				(type default)
			)
			(layer "F.SilkS")
		)
		(fp_line
			(start -0.7874 -0.4064)
			(end 0.7874 -0.4064)
			(stroke
				(width 0.1524)
				(type default)
			)
			(layer "F.SilkS")
		)
		(fp_line
			(start 0.7874 -0.4064)
			(end 0.7874 0.4064)
			(stroke
				(width 0.1524)
				(type default)
			)
			(layer "F.SilkS")
		)
		(fp_poly
			(pts
				(xy -0.508 0.2794) (xy -0.508 0.2286) (xy -0.635 0.2286) (xy -0.635 -0.254) (xy -0.5334 -0.254)
				(xy -0.5334 -0.2794) (xy 0.5334 -0.2794) (xy 0.5334 -0.254) (xy 0.635 -0.254) (xy 0.635 0.254) (xy 0.5334 0.254)
				(xy 0.5334 0.2794)
			)
			(stroke
				(width 0)
				(type default)
			)
			(fill no)
			(layer "F.CrtYd")
		)
		(pad "1" smd rect
			(at 0.40005 0 270)
			(size 0.4572 0.508)
			(layers "F.Cu" "F.Mask" "F.Paste")
			(net "N42126764")
		)
		(pad "2" smd rect
			(at -0.40005 0 270)
			(size 0.4572 0.508)
			(layers "F.Cu" "F.Mask" "F.Paste")
			(net "GND")
		)
	)
	(footprint ""
		(layer "F.Cu")
		(at 77.999844 -32.29991)
		(property "Reference" "H12"
			(at 7.171944 -6.474206 0)
			(unlocked yes)
			(layer "F.SilkS")
			(effects
				(font
					(size 0.7874 0.5842)
					(thickness 0.1524)
				)
				(justify left)
			)
		)
		(property "Value" ""
			(at 0 0 0)
			(layer "F.Fab")
			(effects
				(font
					(size 1.27 1.27)
				)
			)
		)
		(duplicate_pad_numbers_are_jumpers no)
		(fp_circle
			(center 0 0)
			(end 7.999984 0)
			(stroke
				(width 0.1524)
				(type default)
			)
			(fill no)
			(layer "F.SilkS")
		)
		(fp_circle
			(center 0 0)
			(end 14.7066 0)
			(stroke
				(width 0.1524)
				(type default)
			)
			(fill no)
			(layer "B.SilkS")
		)
		(fp_poly
			(pts
				(arc
					(start 5.0038 0)
					(mid -5.0038 0)
					(end 5.0038 0)
				)
			)
			(stroke
				(width 0)
				(type default)
			)
			(fill no)
			(layer "F.CrtYd")
		)
		(pad "" np_thru_hole circle
			(at 0 0)
			(size 4.0132 4.0132)
			(drill 4.0132)
			(layers "*.Cu" "*.Mask")
			(clearance 0.381)
			(thermal_gap 0.381)
		)
		(pad "2" thru_hole circle
			(at 0 -3.50012)
			(size 0.762 0.762)
			(drill 0.5588)
			(layers "*.Cu" "*.Mask")
			(remove_unused_layers no)
			(net "GND")
			(clearance 0.1524)
			(thermal_gap 0.1524)
		)
		(pad "3" thru_hole circle
			(at -2.500122 -2.500122)
			(size 0.762 0.762)
			(drill 0.5588)
			(layers "*.Cu" "*.Mask")
			(remove_unused_layers no)
			(net "GND")
			(clearance 0.1524)
			(thermal_gap 0.1524)
		)
		(pad "4" thru_hole circle
			(at -3.50012 0)
			(size 0.762 0.762)
			(drill 0.5588)
			(layers "*.Cu" "*.Mask")
			(remove_unused_layers no)
			(net "GND")
			(clearance 0.1524)
			(thermal_gap 0.1524)
		)
		(pad "5" thru_hole circle
			(at -2.500122 2.500122)
			(size 0.762 0.762)
			(drill 0.5588)
			(layers "*.Cu" "*.Mask")
			(remove_unused_layers no)
			(net "GND")
			(clearance 0.1524)
			(thermal_gap 0.1524)
		)
		(pad "6" thru_hole circle
			(at 0 3.50012)
			(size 0.762 0.762)
			(drill 0.5588)
			(layers "*.Cu" "*.Mask")
			(remove_unused_layers no)
			(net "GND")
			(clearance 0.1524)
			(thermal_gap 0.1524)
		)
		(pad "7" thru_hole circle
			(at 2.500122 2.500122)
			(size 0.762 0.762)
			(drill 0.5588)
			(layers "*.Cu" "*.Mask")
			(remove_unused_layers no)
			(net "GND")
			(clearance 0.1524)
			(thermal_gap 0.1524)
		)
		(pad "8" thru_hole circle
			(at 3.50012 0)
			(size 0.762 0.762)
			(drill 0.5588)
			(layers "*.Cu" "*.Mask")
			(remove_unused_layers no)
			(net "GND")
			(clearance 0.1524)
			(thermal_gap 0.1524)
		)
		(pad "9" thru_hole circle
			(at 2.500122 -2.500122)
			(size 0.762 0.762)
			(drill 0.5588)
			(layers "*.Cu" "*.Mask")
			(remove_unused_layers no)
			(net "GND")
			(clearance 0.1524)
			(thermal_gap 0.1524)
		)
		(zone
			(layer "F.Cu")
			(hatch none 0.5)
			(connect_pads
				(clearance 0)
			)
			(min_thickness 0.25)
			(keepout
				(tracks not_allowed)
				(vias allowed)
				(pads allowed)
				(copperpour not_allowed)
				(footprints allowed)
			)
			(placement
				(enabled no)
				(sheetname "")
			)
			(fill
				(thermal_gap 0.5)
				(thermal_bridge_width 0.5)
				(island_removal_mode 0)
			)
			(polygon
				(pts
					(arc
						(start 77.999844 -40.30091)
						(mid 69.998844 -32.29991)
						(end 77.999844 -24.29891)
					)
					(arc
						(start 77.999844 -24.29891)
						(mid 79.434944 -25.73401)
						(end 77.999844 -27.16911)
					)
					(arc
						(start 77.999844 -27.16911)
						(mid 72.869044 -32.29991)
						(end 77.999844 -37.43071)
					)
					(arc
						(start 77.999844 -37.43071)
						(mid 79.434944 -38.86581)
						(end 77.999844 -40.30091)
					)
				)
			)
		)
		(zone
			(layer "F.Cu")
			(hatch none 0.5)
			(connect_pads
				(clearance 0)
			)
			(min_thickness 0.25)
			(keepout
				(tracks not_allowed)
				(vias allowed)
				(pads allowed)
				(copperpour not_allowed)
				(footprints allowed)
			)
			(placement
				(enabled no)
				(sheetname "")
			)
			(fill
				(thermal_gap 0.5)
				(thermal_bridge_width 0.5)
				(island_removal_mode 0)
			)
			(polygon
				(pts
					(arc
						(start 77.999844 -40.30091)
						(mid 86.000844 -32.29991)
						(end 77.999844 -24.29891)
					)
					(arc
						(start 77.999844 -24.29891)
						(mid 76.564744 -25.73401)
						(end 77.999844 -27.16911)
					)
					(arc
						(start 77.999844 -27.16911)
						(mid 83.130644 -32.29991)
						(end 77.999844 -37.43071)
					)
					(arc
						(start 77.999844 -37.43071)
						(mid 76.564744 -38.86581)
						(end 77.999844 -40.30091)
					)
				)
			)
		)
		(zone
			(layers "F.Cu" "B.Cu" "In1.Cu" "In2.Cu" "In3.Cu" "In4.Cu" "In5.Cu" "In6.Cu")
			(hatch none 0.5)
			(connect_pads
				(clearance 0)
			)
			(min_thickness 0.25)
			(keepout
				(tracks not_allowed)
				(vias allowed)
				(pads allowed)
				(copperpour not_allowed)
				(footprints allowed)
			)
			(placement
				(enabled no)
				(sheetname "")
			)
			(fill
				(thermal_gap 0.5)
				(thermal_bridge_width 0.5)
				(island_removal_mode 0)
			)
			(polygon
				(pts
					(arc
						(start 80.511904 -32.29991)
						(mid 75.487784 -32.29991)
						(end 80.511904 -32.29991)
					)
				)
			)
		)
	)
	(footprint ""
		(layer "F.Cu")
		(at 77.999844 -341.250016)
		(property "Reference" "H5"
			(at -6.4516 -7.127748 0)
			(unlocked yes)
			(layer "F.SilkS")
			(effects
				(font
					(size 0.7874 0.5842)
					(thickness 0.1524)
				)
				(justify left)
			)
		)
		(property "Value" ""
			(at 0 0 0)
			(layer "F.Fab")
			(effects
				(font
					(size 1.27 1.27)
				)
			)
		)
		(duplicate_pad_numbers_are_jumpers no)
		(fp_circle
			(center 0 0)
			(end 7.999984 0)
			(stroke
				(width 0.1524)
				(type default)
			)
			(fill no)
			(layer "F.SilkS")
		)
		(fp_circle
			(center 0 0)
			(end 14.7066 0)
			(stroke
				(width 0.1524)
				(type default)
			)
			(fill no)
			(layer "B.SilkS")
		)
		(fp_poly
			(pts
				(arc
					(start 5.0038 0)
					(mid -5.0038 0)
					(end 5.0038 0)
				)
			)
			(stroke
				(width 0)
				(type default)
			)
			(fill no)
			(layer "F.CrtYd")
		)
		(pad "" np_thru_hole circle
			(at 0 0)
			(size 4.0132 4.0132)
			(drill 4.0132)
			(layers "*.Cu" "*.Mask")
			(clearance 0.381)
			(thermal_gap 0.381)
		)
		(pad "2" thru_hole circle
			(at 0 -3.50012)
			(size 0.762 0.762)
			(drill 0.5588)
			(layers "*.Cu" "*.Mask")
			(remove_unused_layers no)
			(net "GND")
			(clearance 0.1524)
			(thermal_gap 0.1524)
		)
		(pad "3" thru_hole circle
			(at -2.500122 -2.500122)
			(size 0.762 0.762)
			(drill 0.5588)
			(layers "*.Cu" "*.Mask")
			(remove_unused_layers no)
			(net "GND")
			(clearance 0.1524)
			(thermal_gap 0.1524)
		)
		(pad "4" thru_hole circle
			(at -3.50012 0)
			(size 0.762 0.762)
			(drill 0.5588)
			(layers "*.Cu" "*.Mask")
			(remove_unused_layers no)
			(net "GND")
			(clearance 0.1524)
			(thermal_gap 0.1524)
		)
		(pad "5" thru_hole circle
			(at -2.500122 2.500122)
			(size 0.762 0.762)
			(drill 0.5588)
			(layers "*.Cu" "*.Mask")
			(remove_unused_layers no)
			(net "GND")
			(clearance 0.1524)
			(thermal_gap 0.1524)
		)
		(pad "6" thru_hole circle
			(at 0 3.50012)
			(size 0.762 0.762)
			(drill 0.5588)
			(layers "*.Cu" "*.Mask")
			(remove_unused_layers no)
			(net "GND")
			(clearance 0.1524)
			(thermal_gap 0.1524)
		)
		(pad "7" thru_hole circle
			(at 2.500122 2.500122)
			(size 0.762 0.762)
			(drill 0.5588)
			(layers "*.Cu" "*.Mask")
			(remove_unused_layers no)
			(net "GND")
			(clearance 0.1524)
			(thermal_gap 0.1524)
		)
		(pad "8" thru_hole circle
			(at 3.50012 0)
			(size 0.762 0.762)
			(drill 0.5588)
			(layers "*.Cu" "*.Mask")
			(remove_unused_layers no)
			(net "GND")
			(clearance 0.1524)
			(thermal_gap 0.1524)
		)
		(pad "9" thru_hole circle
			(at 2.500122 -2.500122)
			(size 0.762 0.762)
			(drill 0.5588)
			(layers "*.Cu" "*.Mask")
			(remove_unused_layers no)
			(net "GND")
			(clearance 0.1524)
			(thermal_gap 0.1524)
		)
		(zone
			(layer "F.Cu")
			(hatch none 0.5)
			(connect_pads
				(clearance 0)
			)
			(min_thickness 0.25)
			(keepout
				(tracks not_allowed)
				(vias allowed)
				(pads allowed)
				(copperpour not_allowed)
				(footprints allowed)
			)
			(placement
				(enabled no)
				(sheetname "")
			)
			(fill
				(thermal_gap 0.5)
				(thermal_bridge_width 0.5)
				(island_removal_mode 0)
			)
			(polygon
				(pts
					(arc
						(start 77.999844 -349.251016)
						(mid 69.998844 -341.250016)
						(end 77.999844 -333.249016)
					)
					(arc
						(start 77.999844 -333.249016)
						(mid 79.434944 -334.684116)
						(end 77.999844 -336.119216)
					)
					(arc
						(start 77.999844 -336.119216)
						(mid 72.869044 -341.250016)
						(end 77.999844 -346.380816)
					)
					(arc
						(start 77.999844 -346.380816)
						(mid 79.434944 -347.815916)
						(end 77.999844 -349.251016)
					)
				)
			)
		)
		(zone
			(layer "F.Cu")
			(hatch none 0.5)
			(connect_pads
				(clearance 0)
			)
			(min_thickness 0.25)
			(keepout
				(tracks not_allowed)
				(vias allowed)
				(pads allowed)
				(copperpour not_allowed)
				(footprints allowed)
			)
			(placement
				(enabled no)
				(sheetname "")
			)
			(fill
				(thermal_gap 0.5)
				(thermal_bridge_width 0.5)
				(island_removal_mode 0)
			)
			(polygon
				(pts
					(arc
						(start 77.999844 -349.251016)
						(mid 86.000844 -341.250016)
						(end 77.999844 -333.249016)
					)
					(arc
						(start 77.999844 -333.249016)
						(mid 76.564744 -334.684116)
						(end 77.999844 -336.119216)
					)
					(arc
						(start 77.999844 -336.119216)
						(mid 83.130644 -341.250016)
						(end 77.999844 -346.380816)
					)
					(arc
						(start 77.999844 -346.380816)
						(mid 76.564744 -347.815916)
						(end 77.999844 -349.251016)
					)
				)
			)
		)
		(zone
			(layers "F.Cu" "B.Cu" "In1.Cu" "In2.Cu" "In3.Cu" "In4.Cu" "In5.Cu" "In6.Cu")
			(hatch none 0.5)
			(connect_pads
				(clearance 0)
			)
			(min_thickness 0.25)
			(keepout
				(tracks not_allowed)
				(vias allowed)
				(pads allowed)
				(copperpour not_allowed)
				(footprints allowed)
			)
			(placement
				(enabled no)
				(sheetname "")
			)
			(fill
				(thermal_gap 0.5)
				(thermal_bridge_width 0.5)
				(island_removal_mode 0)
			)
			(polygon
				(pts
					(arc
						(start 80.511904 -341.250016)
						(mid 75.487784 -341.250016)
						(end 80.511904 -341.250016)
					)
				)
			)
		)
	)
	(footprint ""
		(layer "F.Cu")
		(at 39.863776 -199.171814 180)
		(property "Reference" "R2"
			(at -1.93802 0.367792 0)
			(unlocked yes)
			(layer "F.SilkS")
			(effects
				(font
					(size 0.7874 0.5842)
					(thickness 0.1524)
				)
				(justify left)
			)
		)
		(property "Value" ""
			(at 0 0 180)
			(layer "F.Fab")
			(effects
				(font
					(size 1.27 1.27)
				)
			)
		)
		(duplicate_pad_numbers_are_jumpers no)
		(fp_line
			(start 0.7874 0.4064)
			(end -0.7874 0.4064)
			(stroke
				(width 0.1524)
				(type default)
			)
			(layer "F.SilkS")
		)
		(fp_line
			(start 0.7874 -0.4064)
			(end 0.7874 0.4064)
			(stroke
				(width 0.1524)
				(type default)
			)
			(layer "F.SilkS")
		)
		(fp_line
			(start -0.7874 0.4064)
			(end -0.7874 -0.4064)
			(stroke
				(width 0.1524)
				(type default)
			)
			(layer "F.SilkS")
		)
		(fp_line
			(start -0.7874 -0.4064)
			(end 0.7874 -0.4064)
			(stroke
				(width 0.1524)
				(type default)
			)
			(layer "F.SilkS")
		)
		(fp_poly
			(pts
				(xy -0.508 0.2794) (xy -0.508 0.2286) (xy -0.635 0.2286) (xy -0.635 -0.254) (xy -0.5334 -0.254)
				(xy -0.5334 -0.2794) (xy 0.5334 -0.2794) (xy 0.5334 -0.254) (xy 0.635 -0.254) (xy 0.635 0.254) (xy 0.5334 0.254)
				(xy 0.5334 0.2794)
			)
			(stroke
				(width 0)
				(type default)
			)
			(fill no)
			(layer "F.CrtYd")
		)
		(pad "1" smd rect
			(at 0.40005 0 180)
			(size 0.4572 0.508)
			(layers "F.Cu" "F.Mask" "F.Paste")
			(net "PSU3_REMOTE_P")
		)
		(pad "2" smd rect
			(at -0.40005 0 180)
			(size 0.4572 0.508)
			(layers "F.Cu" "F.Mask" "F.Paste")
			(net "P12V")
		)
	)
)
